# T6G (Grand Teton) — schematic netlist excerpt (pin names and nets, part order shuffled) for the footprints in the layout excerpt that follows; sources: Cadence DE-HDL packaged netlist, KiCad conversion of 04192023_DAF0TMB3IC0_F0TG_MB_C_brd_V02_OCP.brd

R6089  Q_RES  10K 1% EMPTY  pkg 0402LF  page 193 : A = PVDDCR_SOC_P0_EN_RC ; B = GND
C2509  Q_CAP  22UF 4V 20% X6S  pkg C0402  page 74 : A = PVDDIO_P1 ; B = GND

(kicad_pcb
	(version 20260206)
	(generator "pcbnew")
	(generator_version "10.0")
	(general
		(thickness 1.6)
		(legacy_teardrops no)
	)
	(paper "A4")
	(title_block
		(title "04192023_DAF0TMB3IC0_F0TG_MB_C_brd_V02_OCP.brd")
		(comment 1 "Grand Teton / footprints 7928-7929 of 8354")
	)
	(layers
		(0 "F.Cu" signal "TOP")
		(4 "In1.Cu" signal "GND")
		(6 "In2.Cu" signal "IN1")
		(8 "In3.Cu" signal "GND1")
		(10 "In4.Cu" signal "IN2")
		(12 "In5.Cu" signal "GND2")
		(14 "In6.Cu" signal "IN3")
		(16 "In7.Cu" signal "GND3")
		(18 "In8.Cu" signal "VCC")
		(20 "In9.Cu" signal "VCC1")
		(22 "In10.Cu" signal "GND4")
		(24 "In11.Cu" signal "IN4")
		(26 "In12.Cu" signal "GND5")
		(28 "In13.Cu" signal "IN5")
		(30 "In14.Cu" signal "GND6")
		(32 "In15.Cu" signal "IN6")
		(34 "In16.Cu" signal "GND7")
		(2 "B.Cu" signal "BOTTOM")
		(9 "F.Adhes" user "F.Adhesive")
		(11 "B.Adhes" user "B.Adhesive")
		(13 "F.Paste" user "Package Geometry/Pastemask Top")
		(15 "B.Paste" user "Package Geometry/Pastemask Bottom")
		(5 "F.SilkS" user "Ref Des/Silkscreen Top")
		(7 "B.SilkS" user "Ref Des/Silkscreen Bottom")
		(1 "F.Mask" user "Board Geometry/Soldermask Top")
		(3 "B.Mask" user "Board Geometry/Soldermask Bottom")
		(17 "Dwgs.User" user "User.Drawings")
		(19 "Cmts.User" user "User.Comments")
		(21 "Eco1.User" user "User.Eco1")
		(23 "Eco2.User" user "User.Eco2")
		(25 "Edge.Cuts" user "Board Geometry/Outline")
		(27 "Margin" user)
		(31 "F.CrtYd" user "Package Geometry/Place Bound Top")
		(29 "B.CrtYd" user "Package Geometry/Place Bound Bottom")
		(35 "F.Fab" user "Ref Des/Assembly Top")
		(33 "B.Fab" user "Ref Des/Assembly Bottom")
	)
	(footprint ""
		(layer "B.Cu")
		(at 105.960164 -261.255256 180)
		(property "Reference" "C2509"
			(at 0 0 0)
			(layer "B.SilkS")
			(hide yes)
			(effects
				(font
					(size 1.27 1.27)
				)
				(justify mirror)
			)
		)
		(property "Value" ""
			(at 0 0 0)
			(layer "B.Fab")
			(effects
				(font
					(size 1.27 1.27)
				)
				(justify mirror)
			)
		)
		(duplicate_pad_numbers_are_jumpers no)
		(fp_line
			(start 0.7874 0.4064)
			(end 0.7874 -0.4064)
			(stroke
				(width 0.1524)
				(type default)
			)
			(layer "B.SilkS")
		)
		(fp_line
			(start 0.7874 -0.4064)
			(end -0.7874 -0.4064)
			(stroke
				(width 0.1524)
				(type default)
			)
			(layer "B.SilkS")
		)
		(fp_line
			(start -0.7874 0.4064)
			(end 0.7874 0.4064)
			(stroke
				(width 0.1524)
				(type default)
			)
			(layer "B.SilkS")
		)
		(fp_line
			(start -0.7874 -0.4064)
			(end -0.7874 0.4064)
			(stroke
				(width 0.1524)
				(type default)
			)
			(layer "B.SilkS")
		)
		(fp_line
			(start 0.67945 0.3048)
			(end 0.67945 -0.305054)
			(stroke
				(width 0.1)
				(type default)
			)
			(layer "B.Fab")
		)
		(fp_line
			(start 0.67945 -0.305054)
			(end 0.12065 -0.305054)
			(stroke
				(width 0.1)
				(type default)
			)
			(layer "B.Fab")
		)
		(fp_line
			(start 0.12065 0.3048)
			(end 0.67945 0.3048)
			(stroke
				(width 0.1)
				(type default)
			)
			(layer "B.Fab")
		)
		(fp_line
			(start 0.12065 0.2794)
			(end 0.12065 0.3048)
			(stroke
				(width 0.1)
				(type default)
			)
			(layer "B.Fab")
		)
		(fp_line
			(start 0.12065 -0.2794)
			(end -0.12065 -0.2794)
			(stroke
				(width 0.1)
				(type default)
			)
			(layer "B.Fab")
		)
		(fp_line
			(start 0.12065 -0.305054)
			(end 0.12065 -0.2794)
			(stroke
				(width 0.1)
				(type default)
			)
			(layer "B.Fab")
		)
		(fp_line
			(start -0.120396 0.3048)
			(end -0.120396 0.2794)
			(stroke
				(width 0.1)
				(type default)
			)
			(layer "B.Fab")
		)
		(fp_line
			(start -0.120396 0.2794)
			(end 0.12065 0.2794)
			(stroke
				(width 0.1)
				(type default)
			)
			(layer "B.Fab")
		)
		(fp_line
			(start -0.12065 -0.2794)
			(end -0.12065 -0.3048)
			(stroke
				(width 0.1)
				(type default)
			)
			(layer "B.Fab")
		)
		(fp_line
			(start -0.12065 -0.3048)
			(end -0.67945 -0.3048)
			(stroke
				(width 0.1)
				(type default)
			)
			(layer "B.Fab")
		)
		(fp_line
			(start -0.67945 0.3048)
			(end -0.120396 0.3048)
			(stroke
				(width 0.1)
				(type default)
			)
			(layer "B.Fab")
		)
		(fp_line
			(start -0.67945 -0.3048)
			(end -0.67945 0.3048)
			(stroke
				(width 0.1)
				(type default)
			)
			(layer "B.Fab")
		)
		(pad "1" smd circle
			(at 0.40005 0)
			(size 0 0)
			(layers "B.Cu" "B.Mask" "B.Paste")
			(net "PVDDIO_P1")
		)
		(pad "2" smd circle
			(at -0.40005 0)
			(size 0 0)
			(layers "B.Cu" "B.Mask" "B.Paste")
			(net "GND")
		)
	)
	(footprint ""
		(layer "B.Cu")
		(at 367.671858 -135.970772)
		(property "Reference" "R6089"
			(at 0 0 0)
			(layer "B.SilkS")
			(hide yes)
			(effects
				(font
					(size 1.27 1.27)
				)
				(justify mirror)
			)
		)
		(property "Value" ""
			(at 0 0 0)
			(layer "B.Fab")
			(effects
				(font
					(size 1.27 1.27)
				)
				(justify mirror)
			)
		)
		(duplicate_pad_numbers_are_jumpers no)
		(fp_line
			(start -0.7874 -0.4064)
			(end -0.7874 0.4064)
			(stroke
				(width 0.1524)
				(type default)
			)
			(layer "B.SilkS")
		)
		(fp_line
			(start -0.7874 0.4064)
			(end 0.7874 0.4064)
			(stroke
				(width 0.1524)
				(type default)
			)
			(layer "B.SilkS")
		)
		(fp_line
			(start 0.7874 -0.4064)
			(end -0.7874 -0.4064)
			(stroke
				(width 0.1524)
				(type default)
			)
			(layer "B.SilkS")
		)
		(fp_line
			(start 0.7874 0.4064)
			(end 0.7874 -0.4064)
			(stroke
				(width 0.1524)
				(type default)
			)
			(layer "B.SilkS")
		)
		(fp_line
			(start -0.67945 -0.3048)
			(end -0.67945 0.3048)
			(stroke
				(width 0.1)
				(type default)
			)
			(layer "B.Fab")
		)
		(fp_line
			(start -0.67945 0.3048)
			(end -0.120396 0.3048)
			(stroke
				(width 0.1)
				(type default)
			)
			(layer "B.Fab")
		)
		(fp_line
			(start -0.12065 -0.3048)
			(end -0.67945 -0.3048)
			(stroke
				(width 0.1)
				(type default)
			)
			(layer "B.Fab")
		)
		(fp_line
			(start -0.12065 -0.2794)
			(end -0.12065 -0.3048)
			(stroke
				(width 0.1)
				(type default)
			)
			(layer "B.Fab")
		)
		(fp_line
			(start -0.120396 0.2794)
			(end 0.12065 0.2794)
			(stroke
				(width 0.1)
				(type default)
			)
			(layer "B.Fab")
		)
		(fp_line
			(start -0.120396 0.3048)
			(end -0.120396 0.2794)
			(stroke
				(width 0.1)
				(type default)
			)
			(layer "B.Fab")
		)
		(fp_line
			(start 0.12065 -0.305054)
			(end 0.12065 -0.2794)
			(stroke
				(width 0.1)
				(type default)
			)
			(layer "B.Fab")
		)
		(fp_line
			(start 0.12065 -0.2794)
			(end -0.12065 -0.2794)
			(stroke
				(width 0.1)
				(type default)
			)
			(layer "B.Fab")
		)
		(fp_line
			(start 0.12065 0.2794)
			(end 0.12065 0.3048)
			(stroke
				(width 0.1)
				(type default)
			)
			(layer "B.Fab")
		)
		(fp_line
			(start 0.12065 0.3048)
			(end 0.67945 0.3048)
			(stroke
				(width 0.1)
				(type default)
			)
			(layer "B.Fab")
		)
		(fp_line
			(start 0.67945 -0.305054)
			(end 0.12065 -0.305054)
			(stroke
				(width 0.1)
				(type default)
			)
			(layer "B.Fab")
		)
		(fp_line
			(start 0.67945 0.3048)
			(end 0.67945 -0.305054)
			(stroke
				(width 0.1)
				(type default)
			)
			(layer "B.Fab")
		)
		(pad "1" smd circle
			(at 0.40005 0 180)
			(size 0 0)
			(layers "B.Cu" "B.Mask" "B.Paste")
			(net "PVDDCR_SOC_P0_EN_RC")
		)
		(pad "2" smd circle
			(at -0.40005 0 180)
			(size 0 0)
			(layers "B.Cu" "B.Mask" "B.Paste")
			(net "GND")
		)
	)
)
